# BASEBOARD_FAB2 (Tioga Pass) — schematic parts with pin connectivity, parts 2375–2375 of 4751; source: Cadence DE-HDL packaged netlist (pstxprt.dat, pstxnet.dat, pstchip.dat)

J6M1  SCONN288_H44441003  SCONN  pkg PIP  page 50
  1  \12v\(1)  = P12V_NVDIMM_DEF
  2  VSS(93)  GROUND  = GND
  3  DQ(4)  BI  = M_D_DQ<4>
  4  VSS(92)  GROUND  = GND
  5  DQ(0)  BI  = M_D_DQ<0>
  6  VSS(91)  GROUND  = GND
  7  DQS9P  BI  = M_D_DQS_DP<9>
  8  DQS9N  BI  = M_D_DQS_DN<9>
  9  VSS(90)  GROUND  = GND
  10  DQ(6)  BI  = M_D_DQ<6>
  11  VSS(89)  GROUND  = GND
  12  DQ(2)  BI  = M_D_DQ<2>
  13  VSS(88)  GROUND  = GND
  14  DQ(12)  BI  = M_D_DQ<12>
  15  VSS(87)  GROUND  = GND
  16  DQ(8)  BI  = M_D_DQ<8>
  17  VSS(86)  GROUND  = GND
  18  DQS10P  BI  = M_D_DQS_DP<10>
  19  DQS10N  BI  = M_D_DQS_DN<10>
  20  VSS(85)  GROUND  = GND
  21  DQ(14)  BI  = M_D_DQ<14>
  22  VSS(84)  GROUND  = GND
  23  DQ(10)  BI  = M_D_DQ<10>
  24  VSS(83)  GROUND  = GND
  25  DQ(20)  BI  = M_D_DQ<20>
  26  VSS(82)  GROUND  = GND
  27  DQ(16)  BI  = M_D_DQ<16>
  28  VSS(81)  GROUND  = GND
  29  DQS11P  BI  = M_D_DQS_DP<11>
  30  DQS11N  BI  = M_D_DQS_DN<11>
  31  VSS(80)  GROUND  = GND
  32  DQ(22)  BI  = M_D_DQ<22>
  33  VSS(79)  GROUND  = GND
  34  DQ(18)  BI  = M_D_DQ<18>
  35  VSS(78)  GROUND  = GND
  36  DQ(28)  BI  = M_D_DQ<28>
  37  VSS(77)  GROUND  = GND
  38  DQ(24)  BI  = M_D_DQ<24>
  39  VSS(76)  GROUND  = GND
  40  DQS12P  BI  = M_D_DQS_DP<12>
  41  DQS12N  BI  = M_D_DQS_DN<12>
  42  VSS(75)  GROUND  = GND
  43  DQ(30)  BI  = M_D_DQ<30>
  44  VSS(74)  GROUND  = GND
  45  DQ(26)  BI  = M_D_DQ<26>
  46  VSS(73)  GROUND  = GND
  47  CB(4)  BI  = M_D_ECC<4>
  48  VSS(72)  GROUND  = GND
  49  CB(0)  BI  = M_D_ECC<0>
  50  VSS(71)  GROUND  = GND
  51  DQS17P  BI  = M_D_DQS_DP<17>
  52  DQS17N  BI  = M_D_DQS_DN<17>
  53  VSS(70)  GROUND  = GND
  54  CB(6)  BI  = M_D_ECC<6>
  55  VSS(69)  GROUND  = GND
  56  CB(2)  BI  = M_D_ECC<2>
  57  VSS(68)  GROUND  = GND
  58  RESET_N  BI  = M_DEF_RST_N
  59  VDD(25)  POWER  = PVDDQ_DEF
  60  CKE(0)  BI  = M_D_CKE<2>
  61  VDD(24)  POWER  = PVDDQ_DEF
  62  ACT_N  BI  = M_D_ACT_N
  63  BG(0)  BI  = M_D_BG<0>
  64  VDD(23)  POWER  = PVDDQ_DEF
  65  A12  BI  = M_D_MA<12>
  66  A9  BI  = M_D_MA<9>
  67  VDD(22)  POWER  = PVDDQ_DEF
  68  A8  BI  = M_D_MA<8>
  69  A6  BI  = M_D_MA<6>
  70  VDD(21)  POWER  = PVDDQ_DEF
  71  A3  BI  = M_D_MA<3>
  72  A1  BI  = M_D_MA<1>
  73  VDD(20)  POWER  = PVDDQ_DEF
  74  CK0P  BI  = M_D_CLK_DP<2>
  75  CK0N  BI  = M_D_CLK_DN<2>
  76  VDD(19)  POWER  = PVDDQ_DEF
  77  VTT(1)  POWER  = PVTT_DEF
  78  EVENT_N  BI  = FM_DIMM_EVENT_COD_N
  79  A0  BI  = M_D_MA<0>
  80  VDD(18)  POWER  = PVDDQ_DEF
  81  BA(0)  BI  = M_D_BA<0>
  82  A16_RAS_N  BI  = M_D_MA<16>
  83  VDD(17)  POWER  = PVDDQ_DEF
  84  S0_N  BI  = M_D_CS_N<4>
  85  VDD(16)  POWER  = PVDDQ_DEF
  86  A15_CAS_N  BI  = M_D_MA<15>
  87  ODT(0)  BI  = M_D_ODT<2>
  88  VDD(15)  POWER  = PVDDQ_DEF
  89  S1_N  BI  = M_D_CS_N<5>
  90  VDD(14)  POWER  = PVDDQ_DEF
  91  ODT(1)  BI  = M_D_ODT<3>
  92  VDD(13)  POWER  = PVDDQ_DEF
  93  S2_N_C(0)  BI  = M_D_CS_N<6>
  94  VSS(67)  GROUND  = GND
  95  DQ(36)  BI  = M_D_DQ<36>
  96  VSS(66)  GROUND  = GND
  97  DQ(32)  BI  = M_D_DQ<32>
  98  VSS(65)  GROUND  = GND
  99  DQS13P  BI  = M_D_DQS_DP<13>
  100  DQS13N  BI  = M_D_DQS_DN<13>
  101  VSS(64)  GROUND  = GND
  102  DQ(38)  BI  = M_D_DQ<38>
  103  VSS(63)  GROUND  = GND
  104  DQ(34)  BI  = M_D_DQ<34>
  105  VSS(62)  GROUND  = GND
  106  DQ(44)  BI  = M_D_DQ<44>
  107  VSS(61)  GROUND  = GND
  108  DQ(40)  BI  = M_D_DQ<40>
  109  VSS(60)  GROUND  = GND
  110  DQS14P  BI  = M_D_DQS_DP<14>
  111  DQS14N  BI  = M_D_DQS_DN<14>
  112  VSS(59)  GROUND  = GND
  113  DQ(46)  BI  = M_D_DQ<46>
  114  VSS(58)  GROUND  = GND
  115  DQ(42)  BI  = M_D_DQ<42>
  116  VSS(57)  GROUND  = GND
  117  DQ(52)  BI  = M_D_DQ<52>
  118  VSS(56)  GROUND  = GND
  119  DQ(48)  BI  = M_D_DQ<48>
  120  VSS(55)  GROUND  = GND
  121  DQS15P  BI  = M_D_DQS_DP<15>
  122  DQS15N  BI  = M_D_DQS_DN<15>
  123  VSS(54)  GROUND  = GND
  124  DQ(54)  BI  = M_D_DQ<54>
  125  VSS(53)  GROUND  = GND
  126  DQ(50)  BI  = M_D_DQ<50>
  127  VSS(52)  GROUND  = GND
  128  DQ(60)  BI  = M_D_DQ<60>
  129  VSS(51)  GROUND  = GND
  130  DQ(56)  BI  = M_D_DQ<56>
  131  VSS(50)  GROUND  = GND
  132  DQS16P  BI  = M_D_DQS_DP<16>
  133  DQS16N  BI  = M_D_DQS_DN<16>
  134  VSS(49)  GROUND  = GND
  135  DQ(62)  BI  = M_D_DQ<62>
  136  VSS(48)  GROUND  = GND
  137  DQ(58)  BI  = M_D_DQ<58>
  138  VSS(47)  GROUND  = GND
  139  SA(0)  BI  = PVPP_DEF
  140  SA(1)  BI  = GND
  141  SCL  BI  = SMB_DDR_DEF_VPP_SCL
  142  VPP(4)  POWER  = PVPP_DEF
  143  VPP(3)  POWER  = PVPP_DEF
  144  RFU(2)  BI  = TP_CH_D_DIMM_D1_RFU_2
  145  \12v\(0)  = P12V_NVDIMM_DEF
  146  VREFCA  BI  = M_D_VREF
  147  VSS(46)  GROUND  = GND
  148  DQ(5)  BI  = M_D_DQ<5>
  149  VSS(45)  GROUND  = GND
  150  DQ(1)  BI  = M_D_DQ<1>
  151  VSS(44)  GROUND  = GND
  152  DQS0N  BI  = M_D_DQS_DN<0>
  153  DQS0P  BI  = M_D_DQS_DP<0>
  154  VSS(43)  GROUND  = GND
  155  DQ(7)  BI  = M_D_DQ<7>
  156  VSS(42)  GROUND  = GND
  157  DQ(3)  BI  = M_D_DQ<3>
  158  VSS(41)  GROUND  = GND
  159  DQ(13)  BI  = M_D_DQ<13>
  160  VSS(40)  GROUND  = GND
  161  DQ(9)  BI  = M_D_DQ<9>
  162  VSS(39)  GROUND  = GND
  163  DQS1N  BI  = M_D_DQS_DN<1>
  164  DQS1P  BI  = M_D_DQS_DP<1>
  165  VSS(38)  GROUND  = GND
  166  DQ(15)  BI  = M_D_DQ<15>
  167  VSS(37)  GROUND  = GND
  168  DQ(11)  BI  = M_D_DQ<11>
  169  VSS(36)  GROUND  = GND
  170  DQ(21)  BI  = M_D_DQ<21>
  171  VSS(35)  GROUND  = GND
  172  DQ(17)  BI  = M_D_DQ<17>
  173  VSS(34)  GROUND  = GND
  174  DQS2N  BI  = M_D_DQS_DN<2>
  175  DQS2P  BI  = M_D_DQS_DP<2>
  176  VSS(33)  GROUND  = GND
  177  DQ(23)  BI  = M_D_DQ<23>
  178  VSS(32)  GROUND  = GND
  179  DQ(19)  BI  = M_D_DQ<19>
  180  VSS(31)  GROUND  = GND
  181  DQ(29)  BI  = M_D_DQ<29>
  182  VSS(30)  GROUND  = GND
  183  DQ(25)  BI  = M_D_DQ<25>
  184  VSS(29)  GROUND  = GND
  185  DQS3N  BI  = M_D_DQS_DN<3>
  186  DQS3P  BI  = M_D_DQS_DP<3>
  187  VSS(28)  GROUND  = GND
  188  DQ(31)  BI  = M_D_DQ<31>
  189  VSS(27)  GROUND  = GND
  190  DQ(27)  BI  = M_D_DQ<27>
  191  VSS(26)  GROUND  = GND
  192  CB(5)  BI  = M_D_ECC<5>
  193  VSS(25)  GROUND  = GND
  194  CB(1)  BI  = M_D_ECC<1>
  195  VSS(24)  GROUND  = GND
  196  DQS8N  BI  = M_D_DQS_DN<8>
  197  DQS8P  BI  = M_D_DQS_DP<8>
  198  VSS(23)  GROUND  = GND
  199  CB(7)  BI  = M_D_ECC<7>
  200  VSS(22)  GROUND  = GND
  201  CB(3)  BI  = M_D_ECC<3>
  202  VSS(21)  GROUND  = GND
  203  CKE(1)  BI  = M_D_CKE<3>
  204  VDD(12)  POWER  = PVDDQ_DEF
  205  RFU(0)  BI  = TP_CH_D_DIMM_D1_RFU_0
  206  VDD(11)  POWER  = PVDDQ_DEF
  207  BG(1)  BI  = M_D_BG<1>
  208  ALERT_N  BI  = M_D_ALERT_N
  209  VDD(10)  POWER  = PVDDQ_DEF
  210  A11  BI  = M_D_MA<11>
  211  A7  BI  = M_D_MA<7>
  212  VDD(9)  POWER  = PVDDQ_DEF
  213  A5  BI  = M_D_MA<5>
  214  A4  BI  = M_D_MA<4>
  215  VDD(8)  POWER  = PVDDQ_DEF
  216  A2  BI  = M_D_MA<2>
  217  VDD(7)  POWER  = PVDDQ_DEF
  218  CK1P  BI  = M_D_CLK_DP<3>
  219  CK1N  BI  = M_D_CLK_DN<3>
  220  VDD(6)  POWER  = PVDDQ_DEF
  221  VTT(0)  POWER  = PVTT_DEF
  222  PAR  BI  = M_D_PAR
  223  VDD(5)  POWER  = PVDDQ_DEF
  224  BA(1)  BI  = M_D_BA<1>
  225  A10  BI  = M_D_MA<10>
  226  VDD(4)  POWER  = PVDDQ_DEF
  227  RFU(1)  BI  = TP_CH_D_DIMM_D1_RFU_1
  228  A14_WE_N  BI  = M_D_MA<14>
  229  VDD(3)  POWER  = PVDDQ_DEF
  230  SAVE_N_NC  BI  = FM_ADR_COMPLETE_DEF_N
  231  VDD(2)  POWER  = PVDDQ_DEF
  232  A13  BI  = M_D_MA<13>
  233  VDD(1)  POWER  = PVDDQ_DEF
  234  A17  BI  = M_D_MA<17>
  235  C(2)  BI  = M_D_C<2>
  236  VDD(0)  POWER  = PVDDQ_DEF
  237  S3_N_C(1)  BI  = M_D_CS_N<7>
  238  SA(2)  BI  = GND
  239  VSS(20)  GROUND  = GND
  240  DQ(37)  BI  = M_D_DQ<37>
  241  VSS(19)  GROUND  = GND
  242  DQ(33)  BI  = M_D_DQ<33>
  243  VSS(18)  GROUND  = GND
  244  DQS4N  BI  = M_D_DQS_DN<4>
  245  DQS4P  BI  = M_D_DQS_DP<4>
  246  VSS(17)  GROUND  = GND
  247  DQ(39)  BI  = M_D_DQ<39>
  248  VSS(16)  GROUND  = GND
  249  DQ(35)  BI  = M_D_DQ<35>
  250  VSS(15)  GROUND  = GND
  251  DQ(45)  BI  = M_D_DQ<45>
  252  VSS(14)  GROUND  = GND
  253  DQ(41)  BI  = M_D_DQ<41>
  254  VSS(13)  GROUND  = GND
  255  DQS5N  BI  = M_D_DQS_DN<5>
  256  DQS5P  BI  = M_D_DQS_DP<5>
  257  VSS(12)  GROUND  = GND
  258  DQ(47)  BI  = M_D_DQ<47>
  259  VSS(11)  GROUND  = GND
  260  DQ(43)  BI  = M_D_DQ<43>
  261  VSS(10)  GROUND  = GND
  262  DQ(53)  BI  = M_D_DQ<53>
  263  VSS(9)  GROUND  = GND
  264  DQ(49)  BI  = M_D_DQ<49>
  265  VSS(8)  GROUND  = GND
  266  DQS6N  BI  = M_D_DQS_DN<6>
  267  DQS6P  BI  = M_D_DQS_DP<6>
  268  VSS(7)  GROUND  = GND
  269  DQ(55)  BI  = M_D_DQ<55>
  270  VSS(6)  GROUND  = GND
  271  DQ(51)  BI  = M_D_DQ<51>
  272  VSS(5)  GROUND  = GND
  273  DQ(61)  BI  = M_D_DQ<61>
  274  VSS(4)  GROUND  = GND
  275  DQ(57)  BI  = M_D_DQ<57>
  276  VSS(3)  GROUND  = GND
  277  DQS7N  BI  = M_D_DQS_DN<7>
  278  DQS7P  BI  = M_D_DQS_DP<7>
  279  VSS(2)  GROUND  = GND
  280  DQ(63)  BI  = M_D_DQ<63>
  281  VSS(1)  GROUND  = GND
  282  DQ(59)  BI  = M_D_DQ<59>
  283  VSS(0)  GROUND  = GND
  284  VDDSPD  BI  = PVPP_DEF
  285  SDA  BI  = SMB_DDR_DEF_VPP_SDA
  286  VPP(1)  POWER  = PVPP_DEF
  287  VPP(0)  POWER  = PVPP_DEF
  288  VPP(2)  POWER  = PVPP_DEF
